FILE_TYPE=LIBRARY_PARTS;
primitive '74LVC1G08W57';
  pin
    'A':
      PIN_NUMBER='(1)';
      INPUT_LOAD='(-0.01,0.01)';
    'B':
      PIN_NUMBER='(2)';
      INPUT_LOAD='(-0.01,0.01)';
    'GND':
      PIN_NUMBER='(3)';
      PINUSE='POWER';
      NO_LOAD_CHECK='Both';
      NO_IO_CHECK='Both';
      NO_ASSERT_CHECK='TRUE';
      NO_DIR_CHECK='TRUE';
      ALLOW_CONNECT='TRUE';
    'Y':
      PIN_NUMBER='(4)';
      OUTPUT_LOAD='(1.0,-1.0)';
    'VCC':
      PIN_NUMBER='(5)';
      PINUSE='POWER';
      NO_LOAD_CHECK='Both';
      NO_IO_CHECK='Both';
      NO_ASSERT_CHECK='TRUE';
      NO_DIR_CHECK='TRUE';
      ALLOW_CONNECT='TRUE';
  end_pin;
  body
    PART_NAME='74LVC1G08W57';
    BODY_NAME='74LVC1G08W57';
    PHYS_DES_PREFIX='U';
    CLASS='IC';
  end_body;
end_primitive;

END.
